(kicad_pcb
	(version 20240108)
	(generator "pcbnew")
	(generator_version "8.0")
	(general
		(thickness 1.62)
		(legacy_teardrops no)
	)
	(paper "A4")
	(title_block
		(title "Jetson Orin Baseboard")
		(date "2025-03-12")
		(rev "1.3.4")
		(company "Antmicro Ltd")
		(comment 1 "www.antmicro.com")
		(comment 9 "footprints 412-413 of 677")
	)
	(layers
		(0 "F.Cu" signal)
		(1 "In1.Cu" signal)
		(2 "In2.Cu" signal)
		(3 "In3.Cu" signal)
		(4 "In4.Cu" jumper)
		(5 "In5.Cu" signal)
		(6 "In6.Cu" signal)
		(31 "B.Cu" signal)
		(32 "B.Adhes" user "B.Adhesive")
		(33 "F.Adhes" user "F.Adhesive")
		(34 "B.Paste" user)
		(35 "F.Paste" user)
		(36 "B.SilkS" user "B.Silkscreen")
		(37 "F.SilkS" user "F.Silkscreen")
		(38 "B.Mask" user)
		(39 "F.Mask" user)
		(40 "Dwgs.User" user "User.Drawings")
		(41 "Cmts.User" user "User.Comments")
		(42 "Eco1.User" user "User.Eco1")
		(43 "Eco2.User" user "User.Eco2")
		(44 "Edge.Cuts" user)
		(45 "Margin" user)
		(46 "B.CrtYd" user "B.Courtyard")
		(47 "F.CrtYd" user "F.Courtyard")
		(48 "B.Fab" user)
		(49 "F.Fab" user)
	)
	(footprint "antmicro-footprints:VQFN-24-1EP_3.8x3.8x1.0mm_P0.5mm"
		(layer "B.Cu")
		(at 99.96 100.24 -90)
		(property "Reference" "U26"
			(at -2.52 0.07 180)
			(layer "B.SilkS")
			(effects
				(font
					(size 0.7 0.7)
					(thickness 0.15)
				)
				(justify left bottom mirror)
			)
		)
		(property "Value" "PI4MSD5V9548AZDEX"
			(at 0 -3.6 90)
			(layer "B.Fab")
			(effects
				(font
					(size 0.7 0.7)
					(thickness 0.15)
				)
				(justify right bottom mirror)
			)
		)
		(property "Footprint" "antmicro-footprints:VQFN-24-1EP_3.8x3.8x1.0mm_P0.5mm"
			(at 0 0 -90)
			(layer "F.Fab")
			(hide yes)
			(effects
				(font
					(size 1.27 1.27)
					(thickness 0.15)
				)
			)
		)
		(property "Datasheet" "https://www.mouser.com/datasheet/2/115/DIOD_S_A0003139195_1-2542233.pdf"
			(at 0 0 -90)
			(layer "F.Fab")
			(hide yes)
			(effects
				(font
					(size 1.27 1.27)
					(thickness 0.15)
				)
			)
		)
		(property "Author" "Antmicro"
			(at -0.28 200.2 0)
			(layer "B.Fab")
			(hide yes)
			(effects
				(font
					(size 1 1)
					(thickness 0.15)
				)
				(justify mirror)
			)
		)
		(property "License" "Apache-2.0"
			(at -0.28 200.2 0)
			(layer "B.Fab")
			(hide yes)
			(effects
				(font
					(size 1 1)
					(thickness 0.15)
				)
				(justify mirror)
			)
		)
		(property "MPN" "PI4MSD5V9548AZDEX"
			(at -0.28 200.2 0)
			(layer "B.Fab")
			(hide yes)
			(effects
				(font
					(size 1 1)
					(thickness 0.15)
				)
				(justify mirror)
			)
		)
		(property "Manufacturer" "Diodes Incorporated"
			(at -0.28 200.2 0)
			(layer "B.Fab")
			(hide yes)
			(effects
				(font
					(size 1 1)
					(thickness 0.15)
				)
				(justify mirror)
			)
		)
		(sheetname "CSI")
		(sheetfile "csi.kicad_sch")
		(attr smd)
		(fp_line
			(start -1.524 1.905)
			(end -1.905 1.524)
			(stroke
				(width 0.15)
				(type solid)
			)
			(layer "B.SilkS")
		)
		(fp_line
			(start 1.523 1.905)
			(end 1.904 1.905)
			(stroke
				(width 0.15)
				(type solid)
			)
			(layer "B.SilkS")
		)
		(fp_line
			(start 1.904 1.905)
			(end 1.904 1.524)
			(stroke
				(width 0.15)
				(type solid)
			)
			(layer "B.SilkS")
		)
		(fp_line
			(start 1.904 -1.523)
			(end 1.904 -1.904)
			(stroke
				(width 0.15)
				(type solid)
			)
			(layer "B.SilkS")
		)
		(fp_line
			(start -1.905 -1.904)
			(end -1.905 -1.523)
			(stroke
				(width 0.15)
				(type solid)
			)
			(layer "B.SilkS")
		)
		(fp_line
			(start -1.524 -1.904)
			(end -1.905 -1.904)
			(stroke
				(width 0.15)
				(type solid)
			)
			(layer "B.SilkS")
		)
		(fp_line
			(start 1.904 -1.904)
			(end 1.523 -1.904)
			(stroke
				(width 0.15)
				(type solid)
			)
			(layer "B.SilkS")
		)
		(fp_circle
			(center -2.2 2.2)
			(end -2.15 2.2)
			(stroke
				(width 0.15)
				(type solid)
			)
			(fill solid)
			(layer "B.SilkS")
		)
		(fp_rect
			(start -2.5 2.5)
			(end 2.5 -2.5)
			(stroke
				(width 0.05)
				(type solid)
			)
			(fill none)
			(layer "B.CrtYd")
		)
		(fp_line
			(start -1.524 1.905)
			(end -1.905 1.524)
			(stroke
				(width 0.15)
				(type solid)
			)
			(layer "B.Fab")
		)
		(fp_rect
			(start -1.905 -1.904)
			(end 1.904 1.905)
			(stroke
				(width 0.15)
				(type solid)
			)
			(fill none)
			(layer "B.Fab")
		)
		(fp_text user "License: Apache-2.0"
			(at -2.286 -7.32 90)
			(layer "B.Fab")
			(hide yes)
			(effects
				(font
					(size 0.7 0.7)
					(thickness 0.15)
				)
				(justify left bottom mirror)
			)
		)
		(fp_text user "Author: Antmicro"
			(at -2.286 -6.119 90)
			(layer "B.Fab")
			(hide yes)
			(effects
				(font
					(size 0.7 0.7)
					(thickness 0.15)
				)
				(justify left bottom mirror)
			)
		)
		(fp_text user "${REFERENCE}"
			(at -2.286 -4.919 90)
			(layer "B.Fab")
			(hide yes)
			(effects
				(font
					(size 0.7 0.7)
					(thickness 0.15)
				)
				(justify left bottom mirror)
			)
		)
		(pad "1" smd roundrect
			(at -1.901 1.25 180)
			(size 0.25 0.6)
			(layers "B.Cu" "B.Paste" "B.Mask")
			(roundrect_rratio 0.25)
			(net 320 "/CSI/SDA_CAM0")
			(pinfunction "SD0")
			(pintype "bidirectional")
		)
		(pad "2" smd roundrect
			(at -1.901 0.75 180)
			(size 0.25 0.6)
			(layers "B.Cu" "B.Paste" "B.Mask")
			(roundrect_rratio 0.25)
			(net 323 "/CSI/SCL_CAM0")
			(pinfunction "SC0")
			(pintype "bidirectional")
		)
		(pad "3" smd roundrect
			(at -1.901 0.25 180)
			(size 0.25 0.6)
			(layers "B.Cu" "B.Paste" "B.Mask")
			(roundrect_rratio 0.25)
			(net 329 "/CSI/SDA_CAM1")
			(pinfunction "SD1")
			(pintype "bidirectional")
		)
		(pad "4" smd roundrect
			(at -1.901 -0.248 180)
			(size 0.25 0.6)
			(layers "B.Cu" "B.Paste" "B.Mask")
			(roundrect_rratio 0.25)
			(net 330 "/CSI/SCL_CAM1")
			(pinfunction "SC1")
			(pintype "bidirectional")
		)
		(pad "5" smd roundrect
			(at -1.901 -0.748 180)
			(size 0.25 0.6)
			(layers "B.Cu" "B.Paste" "B.Mask")
			(roundrect_rratio 0.25)
			(net 331 "/CSI/SDA_CAM2")
			(pinfunction "SD2")
			(pintype "bidirectional")
		)
		(pad "6" smd roundrect
			(at -1.901 -1.249 180)
			(size 0.25 0.6)
			(layers "B.Cu" "B.Paste" "B.Mask")
			(roundrect_rratio 0.25)
			(net 333 "/CSI/SCL_CAM2")
			(pinfunction "SC2")
			(pintype "bidirectional")
		)
		(pad "7" smd roundrect
			(at -1.252 -1.898 90)
			(size 0.25 0.6)
			(layers "B.Cu" "B.Paste" "B.Mask")
			(roundrect_rratio 0.25)
			(net 336 "/CSI/SDA_CAM3")
			(pinfunction "SD3")
			(pintype "bidirectional")
		)
		(pad "8" smd roundrect
			(at -0.751 -1.898 90)
			(size 0.25 0.6)
			(layers "B.Cu" "B.Paste" "B.Mask")
			(roundrect_rratio 0.25)
			(net 337 "/CSI/SCL_CAM3")
			(pinfunction "SC3")
			(pintype "bidirectional")
		)
		(pad "9" smd roundrect
			(at -0.25 -1.898 90)
			(size 0.25 0.6)
			(layers "B.Cu" "B.Paste" "B.Mask")
			(roundrect_rratio 0.25)
			(net 1 "GND")
			(pinfunction "GND")
			(pintype "power_in")
		)
		(pad "10" smd roundrect
			(at 0.248 -1.898 90)
			(size 0.25 0.6)
			(layers "B.Cu" "B.Paste" "B.Mask")
			(roundrect_rratio 0.25)
			(net 535 "/CSI/MUX_I2C_4_SDA")
			(pinfunction "SD4")
			(pintype "bidirectional")
		)
		(pad "11" smd roundrect
			(at 0.748 -1.898 90)
			(size 0.25 0.6)
			(layers "B.Cu" "B.Paste" "B.Mask")
			(roundrect_rratio 0.25)
			(net 536 "/CSI/MUX_I2C_4_SCL")
			(pinfunction "SC4")
			(pintype "bidirectional")
		)
		(pad "12" smd roundrect
			(at 1.249 -1.898 90)
			(size 0.25 0.6)
			(layers "B.Cu" "B.Paste" "B.Mask")
			(roundrect_rratio 0.25)
			(net 537 "/CSI/MUX_I2C_5_SDA")
			(pinfunction "SD5")
			(pintype "bidirectional")
		)
		(pad "13" smd roundrect
			(at 1.898 -1.249)
			(size 0.25 0.6)
			(layers "B.Cu" "B.Paste" "B.Mask")
			(roundrect_rratio 0.25)
			(net 538 "/CSI/MUX_I2C_5_SCL")
			(pinfunction "SC5")
			(pintype "bidirectional")
		)
		(pad "14" smd roundrect
			(at 1.898 -0.748)
			(size 0.25 0.6)
			(layers "B.Cu" "B.Paste" "B.Mask")
			(roundrect_rratio 0.25)
			(net 539 "/CSI/MUX_I2C_6_SDA")
			(pinfunction "SD6")
			(pintype "bidirectional")
		)
		(pad "15" smd roundrect
			(at 1.898 -0.248)
			(size 0.25 0.6)
			(layers "B.Cu" "B.Paste" "B.Mask")
			(roundrect_rratio 0.25)
			(net 542 "/CSI/MUX_I2C_6_SCL")
			(pinfunction "SC6")
			(pintype "bidirectional")
		)
		(pad "16" smd roundrect
			(at 1.898 0.25)
			(size 0.25 0.6)
			(layers "B.Cu" "B.Paste" "B.Mask")
			(roundrect_rratio 0.25)
			(net 543 "/CSI/MUX_I2C_7_SDA")
			(pinfunction "SD7")
			(pintype "bidirectional")
		)
		(pad "17" smd roundrect
			(at 1.898 0.75)
			(size 0.25 0.6)
			(layers "B.Cu" "B.Paste" "B.Mask")
			(roundrect_rratio 0.25)
			(net 544 "/CSI/MUX_I2C_7_SCL")
			(pinfunction "SC7")
			(pintype "bidirectional")
		)
		(pad "18" smd roundrect
			(at 1.898 1.252)
			(size 0.25 0.6)
			(layers "B.Cu" "B.Paste" "B.Mask")
			(roundrect_rratio 0.25)
			(net 1 "GND")
			(pinfunction "A2")
			(pintype "input")
		)
		(pad "19" smd roundrect
			(at 1.249 1.901 270)
			(size 0.25 0.6)
			(layers "B.Cu" "B.Paste" "B.Mask")
			(roundrect_rratio 0.25)
			(net 512 "/CSI/I2C_MUX_SCL")
			(pinfunction "SCL")
			(pintype "bidirectional")
		)
		(pad "20" smd roundrect
			(at 0.748 1.901 270)
			(size 0.25 0.6)
			(layers "B.Cu" "B.Paste" "B.Mask")
			(roundrect_rratio 0.25)
			(net 511 "/CSI/I2C_MUX_SDA")
			(pinfunction "SDA")
			(pintype "bidirectional")
		)
		(pad "21" smd roundrect
			(at 0.248 1.901 270)
			(size 0.25 0.6)
			(layers "B.Cu" "B.Paste" "B.Mask")
			(roundrect_rratio 0.25)
			(net 112 "+1V8")
			(pinfunction "VCC")
			(pintype "power_in")
		)
		(pad "22" smd roundrect
			(at -0.25 1.901 270)
			(size 0.25 0.6)
			(layers "B.Cu" "B.Paste" "B.Mask")
			(roundrect_rratio 0.25)
			(net 325 "/CSI/I2C_MUX_A0")
			(pinfunction "A0")
			(pintype "input")
		)
		(pad "23" smd roundrect
			(at -0.75 1.901 270)
			(size 0.25 0.6)
			(layers "B.Cu" "B.Paste" "B.Mask")
			(roundrect_rratio 0.25)
			(net 1 "GND")
			(pinfunction "A1")
			(pintype "input")
		)
		(pad "24" smd roundrect
			(at -1.252 1.901 270)
			(size 0.25 0.6)
			(layers "B.Cu" "B.Paste" "B.Mask")
			(roundrect_rratio 0.25)
			(net 324 "/CSI/I2C_MUX_RESET")
			(pinfunction "~{RESET}")
			(pintype "input")
		)
		(pad "25" smd roundrect
			(at 0 0.001 270)
			(size 2.1 2.1)
			(layers "B.Cu" "B.Paste" "B.Mask")
			(roundrect_rratio 0.05)
			(net 710 "unconnected-(U26-EP-Pad25)")
			(pinfunction "EP")
			(pintype "power_in+no_connect")
		)
	)
	(footprint "antmicro-footprints:R_0402_1005Metric"
		(layer "B.Cu")
		(at 59.14 98.62 90)
		(descr "Resistor SMD 0402")
		(tags "resistor SMD 0402")
		(property "Reference" "R70"
			(at -3.03 0.5 90)
			(layer "B.SilkS")
			(effects
				(font
					(size 0.7 0.7)
					(thickness 0.15)
				)
				(justify right bottom mirror)
			)
		)
		(property "Value" "R_0R_0402"
			(at 0 -1.4 90)
			(layer "B.Fab")
			(effects
				(font
					(size 0.7 0.7)
					(thickness 0.15)
				)
				(justify right bottom mirror)
			)
		)
		(property "Footprint" "antmicro-footprints:R_0402_1005Metric"
			(at 0 0 90)
			(layer "F.Fab")
			(hide yes)
			(effects
				(font
					(size 1.27 1.27)
					(thickness 0.15)
				)
			)
		)
		(property "Datasheet" "https://industrial.panasonic.com/cdbs/www-data/pdf/RDA0000/AOA0000C301.pdf"
			(at 0 0 90)
			(layer "F.Fab")
			(hide yes)
			(effects
				(font
					(size 1.27 1.27)
					(thickness 0.15)
				)
			)
		)
		(property "Author" "Antmicro"
			(at 157.76 39.48 0)
			(layer "B.Fab")
			(hide yes)
			(effects
				(font
					(size 1 1)
					(thickness 0.15)
				)
				(justify mirror)
			)
		)
		(property "Current" "1A"
			(at 157.76 39.48 0)
			(layer "B.Fab")
			(hide yes)
			(effects
				(font
					(size 1 1)
					(thickness 0.15)
				)
				(justify mirror)
			)
		)
		(property "License" "Apache-2.0"
			(at 157.76 39.48 0)
			(layer "B.Fab")
			(hide yes)
			(effects
				(font
					(size 1 1)
					(thickness 0.15)
				)
				(justify mirror)
			)
		)
		(property "MPN" "ERJ2GE0R00X"
			(at 157.76 39.48 0)
			(layer "B.Fab")
			(hide yes)
			(effects
				(font
					(size 1 1)
					(thickness 0.15)
				)
				(justify mirror)
			)
		)
		(property "Manufacturer" "Panasonic"
			(at 157.76 39.48 0)
			(layer "B.Fab")
			(hide yes)
			(effects
				(font
					(size 1 1)
					(thickness 0.15)
				)
				(justify mirror)
			)
		)
		(property "Tolerance" ""
			(at 157.76 39.48 0)
			(layer "B.Fab")
			(hide yes)
			(effects
				(font
					(size 1 1)
					(thickness 0.15)
				)
				(justify mirror)
			)
		)
		(property "Val" "0R"
			(at 157.76 39.48 0)
			(layer "B.Fab")
			(hide yes)
			(effects
				(font
					(size 1 1)
					(thickness 0.15)
				)
				(justify mirror)
			)
		)
		(sheetname "USB Debug, DP")
		(sheetfile "usb.kicad_sch")
		(attr smd)
		(fp_rect
			(start -0.925 0.47)
			(end 0.925 -0.47)
			(stroke
				(width 0.05)
				(type default)
			)
			(fill none)
			(layer "B.CrtYd")
		)
		(fp_rect
			(start -0.5 0.25)
			(end 0.5 -0.25)
			(stroke
				(width 0.15)
				(type solid)
			)
			(fill none)
			(layer "B.Fab")
		)
		(fp_text user "License: Apache-2.0"
			(at -0.95 -5.169 90)
			(layer "B.Fab")
			(hide yes)
			(effects
				(font
					(size 0.7 0.7)
					(thickness 0.15)
				)
				(justify right bottom mirror)
			)
		)
		(fp_text user "${REFERENCE}"
			(at -0.95 -3.168 90)
			(layer "B.Fab")
			(hide yes)
			(effects
				(font
					(size 0.7 0.7)
					(thickness 0.15)
				)
				(justify right bottom mirror)
			)
		)
		(fp_text user "Author: Antmicro"
			(at -0.95 -4.169 90)
			(layer "B.Fab")
			(hide yes)
			(effects
				(font
					(size 0.7 0.7)
					(thickness 0.15)
				)
				(justify right bottom mirror)
			)
		)
		(pad "1" smd roundrect
			(at -0.48 0 90)
			(size 0.59 0.64)
			(layers "B.Cu" "B.Paste" "B.Mask")
			(roundrect_rratio 0.25)
			(net 252 "SYS_SCL")
			(pintype "passive")
		)
		(pad "2" smd roundrect
			(at 0.48 0 90)
			(size 0.59 0.64)
			(layers "B.Cu" "B.Paste" "B.Mask")
			(roundrect_rratio 0.25)
			(net 302 "/USB Debug, DP/PDC_I2C1_SCL")
			(pintype "passive")
		)
	)
)
